(kicad_pcb
	(version 20260206)
	(generator "pcbnew")
	(generator_version "10.0")
	(general
		(thickness 1.6)
		(legacy_teardrops no)
	)
	(paper "A4")
	(title_block
		(title "peb — Lightning_PEB_BRD.brd")
		(comment 1 "Lightning (Wiwynn / Facebook NVMe JBOF) / footprints 416-422 of 2563")
	)
	(layers
		(0 "F.Cu" signal "TOP")
		(4 "In1.Cu" signal "L2GND")
		(6 "In2.Cu" signal "L3")
		(8 "In3.Cu" signal "L4VCC")
		(10 "In4.Cu" signal "L5VCC")
		(12 "In5.Cu" signal "L6")
		(14 "In6.Cu" signal "L7GND")
		(2 "B.Cu" signal "BOTTOM")
		(9 "F.Adhes" user "F.Adhesive")
		(11 "B.Adhes" user "B.Adhesive")
		(13 "F.Paste" user "Package Geometry/Pastemask Top")
		(15 "B.Paste" user "Package Geometry/Pastemask Bottom")
		(5 "F.SilkS" user "Ref Des/Silkscreen Top")
		(7 "B.SilkS" user "Ref Des/Silkscreen Bottom")
		(1 "F.Mask" user "Board Geometry/Soldermask Top")
		(3 "B.Mask" user "Board Geometry/Soldermask Bottom")
		(17 "Dwgs.User" user "User.Drawings")
		(19 "Cmts.User" user "User.Comments")
		(21 "Eco1.User" user "User.Eco1")
		(23 "Eco2.User" user "User.Eco2")
		(25 "Edge.Cuts" user "Board Geometry/Outline")
		(27 "Margin" user)
		(31 "F.CrtYd" user "Package Geometry/Place Bound Top")
		(29 "B.CrtYd" user "Package Geometry/Place Bound Bottom")
		(35 "F.Fab" user "Ref Des/Assembly Top")
		(33 "B.Fab" user "Ref Des/Assembly Bottom")
	)
	(footprint ""
		(layer "F.Cu")
		(at 229.108 -87.7824 -90)
		(property "Reference" "R178"
			(at 0 0 270)
			(layer "F.SilkS")
			(hide yes)
			(effects
				(font
					(size 1.27 1.27)
				)
			)
		)
		(property "Value" "4K7R2F-GP"
			(at 0.064008 -3.993896 270)
			(unlocked yes)
			(layer "F.Fab")
			(hide yes)
			(effects
				(font
					(size 1.016 1.016)
					(thickness 0.1524)
				)
			)
		)
		(property "Device Type" "R402H16"
			(at 0.064008 -5.517896 270)
			(unlocked yes)
			(layer "F.Fab")
			(hide yes)
			(effects
				(font
					(size 1.016 1.016)
					(thickness 0.1524)
				)
			)
		)
		(duplicate_pad_numbers_are_jumpers no)
		(fp_line
			(start -0.508 -0.9398)
			(end -0.508 0.9398)
			(stroke
				(width 0.1524)
				(type default)
			)
			(layer "F.SilkS")
		)
		(fp_line
			(start 0.508 -0.9398)
			(end -0.508 -0.9398)
			(stroke
				(width 0.1524)
				(type default)
			)
			(layer "F.SilkS")
		)
		(fp_rect
			(start -0.508 0.9398)
			(end 0.508 -0.9398)
			(stroke
				(width 0)
				(type default)
			)
			(fill no)
			(layer "F.CrtYd")
		)
		(fp_rect
			(start -0.508 0.9398)
			(end 0.508 -0.9398)
			(stroke
				(width 0)
				(type default)
			)
			(fill no)
			(layer "F.Fab")
		)
		(pad "1" smd custom
			(at 0 -0.4445 270)
			(size 0.1397 0.1397)
			(layers "F.Cu" "F.Mask" "F.Paste")
			(net "P3V3_STBY")
			(options
				(clearance outline)
				(anchor circle)
			)
			(primitives
				(gr_poly
					(pts
						(arc
							(start -0.1778 -0.2794)
							(mid -0.249642 -0.249642)
							(end -0.2794 -0.1778)
						)
						(arc
							(start -0.2794 0.1778)
							(mid -0.249642 0.249642)
							(end -0.1778 0.2794)
						)
						(arc
							(start 0.1778 0.2794)
							(mid 0.249642 0.249642)
							(end 0.2794 0.1778)
						)
						(arc
							(start 0.2794 -0.1778)
							(mid 0.249642 -0.249642)
							(end 0.1778 -0.2794)
						)
					)
					(width 0)
					(fill yes)
				)
			)
		)
		(pad "2" smd custom
			(at 0 0.4445 270)
			(size 0.1397 0.1397)
			(layers "F.Cu" "F.Mask" "F.Paste")
			(net "TEMP_3_A2")
			(options
				(clearance outline)
				(anchor circle)
			)
			(primitives
				(gr_poly
					(pts
						(arc
							(start -0.1778 -0.2794)
							(mid -0.249642 -0.249642)
							(end -0.2794 -0.1778)
						)
						(arc
							(start -0.2794 0.1778)
							(mid -0.249642 0.249642)
							(end -0.1778 0.2794)
						)
						(arc
							(start 0.1778 0.2794)
							(mid 0.249642 0.249642)
							(end 0.2794 0.1778)
						)
						(arc
							(start 0.2794 -0.1778)
							(mid 0.249642 -0.249642)
							(end 0.1778 -0.2794)
						)
					)
					(width 0)
					(fill yes)
				)
			)
		)
	)
	(footprint ""
		(layer "F.Cu")
		(at 26.035 -75.9206 -90)
		(property "Reference" "R393"
			(at 0 0 270)
			(layer "F.SilkS")
			(hide yes)
			(effects
				(font
					(size 1.27 1.27)
				)
			)
		)
		(property "Value" "10KR2F-2-GP"
			(at 0.064008 -3.993896 270)
			(unlocked yes)
			(layer "F.Fab")
			(hide yes)
			(effects
				(font
					(size 1.016 1.016)
					(thickness 0.1524)
				)
			)
		)
		(property "Device Type" "R402H16"
			(at 0.064008 -5.517896 270)
			(unlocked yes)
			(layer "F.Fab")
			(hide yes)
			(effects
				(font
					(size 1.016 1.016)
					(thickness 0.1524)
				)
			)
		)
		(duplicate_pad_numbers_are_jumpers no)
		(fp_line
			(start -0.508 -0.9398)
			(end -0.508 0.9398)
			(stroke
				(width 0.1524)
				(type default)
			)
			(layer "F.SilkS")
		)
		(fp_line
			(start 0.508 -0.9398)
			(end -0.508 -0.9398)
			(stroke
				(width 0.1524)
				(type default)
			)
			(layer "F.SilkS")
		)
		(fp_rect
			(start -0.508 0.9398)
			(end 0.508 -0.9398)
			(stroke
				(width 0)
				(type default)
			)
			(fill no)
			(layer "F.CrtYd")
		)
		(fp_rect
			(start -0.508 0.9398)
			(end 0.508 -0.9398)
			(stroke
				(width 0)
				(type default)
			)
			(fill no)
			(layer "F.Fab")
		)
		(pad "1" smd custom
			(at 0 -0.4445 270)
			(size 0.1397 0.1397)
			(layers "F.Cu" "F.Mask" "F.Paste")
			(net "P3V3_STBY")
			(options
				(clearance outline)
				(anchor circle)
			)
			(primitives
				(gr_poly
					(pts
						(arc
							(start -0.1778 -0.2794)
							(mid -0.249642 -0.249642)
							(end -0.2794 -0.1778)
						)
						(arc
							(start -0.2794 0.1778)
							(mid -0.249642 0.249642)
							(end -0.1778 0.2794)
						)
						(arc
							(start 0.1778 0.2794)
							(mid 0.249642 0.249642)
							(end 0.2794 0.1778)
						)
						(arc
							(start 0.2794 -0.1778)
							(mid 0.249642 -0.249642)
							(end 0.1778 -0.2794)
						)
					)
					(width 0)
					(fill yes)
				)
			)
		)
		(pad "2" smd custom
			(at 0 0.4445 270)
			(size 0.1397 0.1397)
			(layers "F.Cu" "F.Mask" "F.Paste")
			(net "RMII_BMC_PHY_TXD1")
			(options
				(clearance outline)
				(anchor circle)
			)
			(primitives
				(gr_poly
					(pts
						(arc
							(start -0.1778 -0.2794)
							(mid -0.249642 -0.249642)
							(end -0.2794 -0.1778)
						)
						(arc
							(start -0.2794 0.1778)
							(mid -0.249642 0.249642)
							(end -0.1778 0.2794)
						)
						(arc
							(start 0.1778 0.2794)
							(mid 0.249642 0.249642)
							(end 0.2794 0.1778)
						)
						(arc
							(start 0.2794 -0.1778)
							(mid 0.249642 -0.249642)
							(end 0.1778 -0.2794)
						)
					)
					(width 0)
					(fill yes)
				)
			)
		)
	)
	(footprint ""
		(layer "F.Cu")
		(at 267.592048 -212.420454 180)
		(property "Reference" "C105"
			(at 0 0 180)
			(layer "F.SilkS")
			(hide yes)
			(effects
				(font
					(size 1.27 1.27)
				)
			)
		)
		(property "Value" "SCD22U10V2KX-1GP"
			(at 1.1811 -2.7051 180)
			(unlocked yes)
			(layer "F.Fab")
			(hide yes)
			(effects
				(font
					(size 1.016 1.016)
					(thickness 0.1524)
				)
			)
		)
		(property "Device Type" "C402H22"
			(at 1.1811 -4.2291 180)
			(unlocked yes)
			(layer "F.Fab")
			(hide yes)
			(effects
				(font
					(size 1.016 1.016)
					(thickness 0.1524)
				)
			)
		)
		(duplicate_pad_numbers_are_jumpers no)
		(fp_rect
			(start -0.4318 0.9525)
			(end 0.4318 -0.9525)
			(stroke
				(width 0)
				(type default)
			)
			(fill no)
			(layer "F.CrtYd")
		)
		(fp_rect
			(start -0.4318 0.9525)
			(end 0.4318 -0.9525)
			(stroke
				(width 0)
				(type default)
			)
			(fill no)
			(layer "F.Fab")
		)
		(pad "1" smd custom
			(at 0 -0.4445 180)
			(size 0.1524 0.1524)
			(layers "F.Cu" "F.Mask" "F.Paste")
			(net "PCIE_TX_CAP_P36")
			(options
				(clearance outline)
				(anchor circle)
			)
			(primitives
				(gr_poly
					(pts
						(arc
							(start 0.3048 -0.2032)
							(mid 0.275042 -0.275042)
							(end 0.2032 -0.3048)
						)
						(arc
							(start -0.2032 -0.3048)
							(mid -0.275042 -0.275042)
							(end -0.3048 -0.2032)
						)
						(arc
							(start -0.3048 0.2032)
							(mid -0.275042 0.275042)
							(end -0.2032 0.3048)
						)
						(arc
							(start 0.2032 0.3048)
							(mid 0.275042 0.275042)
							(end 0.3048 0.2032)
						)
					)
					(width 0)
					(fill yes)
				)
			)
		)
		(pad "2" smd custom
			(at 0 0.4445 180)
			(size 0.1524 0.1524)
			(layers "F.Cu" "F.Mask" "F.Paste")
			(net "PCIE_TX_P36")
			(options
				(clearance outline)
				(anchor circle)
			)
			(primitives
				(gr_poly
					(pts
						(arc
							(start 0.3048 -0.2032)
							(mid 0.275042 -0.275042)
							(end 0.2032 -0.3048)
						)
						(arc
							(start -0.2032 -0.3048)
							(mid -0.275042 -0.275042)
							(end -0.3048 -0.2032)
						)
						(arc
							(start -0.3048 0.2032)
							(mid -0.275042 0.275042)
							(end -0.2032 0.3048)
						)
						(arc
							(start 0.2032 0.3048)
							(mid 0.275042 0.275042)
							(end 0.3048 0.2032)
						)
					)
					(width 0)
					(fill yes)
				)
			)
		)
	)
	(footprint ""
		(layer "F.Cu")
		(at 48.518572 -50.306224)
		(property "Reference" "R499"
			(at 0 0 0)
			(layer "F.SilkS")
			(hide yes)
			(effects
				(font
					(size 1.27 1.27)
				)
			)
		)
		(property "Value" "3K3R2F-2-GP"
			(at 0.064008 -3.993896 0)
			(unlocked yes)
			(layer "F.Fab")
			(hide yes)
			(effects
				(font
					(size 1.016 1.016)
					(thickness 0.1524)
				)
			)
		)
		(property "Device Type" "R402H16"
			(at 0.064008 -5.517896 0)
			(unlocked yes)
			(layer "F.Fab")
			(hide yes)
			(effects
				(font
					(size 1.016 1.016)
					(thickness 0.1524)
				)
			)
		)
		(duplicate_pad_numbers_are_jumpers no)
		(fp_line
			(start -0.508 -0.9398)
			(end -0.508 0.9398)
			(stroke
				(width 0.1524)
				(type default)
			)
			(layer "F.SilkS")
		)
		(fp_line
			(start 0.508 -0.9398)
			(end -0.508 -0.9398)
			(stroke
				(width 0.1524)
				(type default)
			)
			(layer "F.SilkS")
		)
		(fp_rect
			(start -0.508 0.9398)
			(end 0.508 -0.9398)
			(stroke
				(width 0)
				(type default)
			)
			(fill no)
			(layer "F.CrtYd")
		)
		(fp_rect
			(start -0.508 0.9398)
			(end 0.508 -0.9398)
			(stroke
				(width 0)
				(type default)
			)
			(fill no)
			(layer "F.Fab")
		)
		(pad "1" smd custom
			(at 0 -0.4445)
			(size 0.1397 0.1397)
			(layers "F.Cu" "F.Mask" "F.Paste")
			(net "NVM_SI_R")
			(options
				(clearance outline)
				(anchor circle)
			)
			(primitives
				(gr_poly
					(pts
						(arc
							(start -0.1778 -0.2794)
							(mid -0.249642 -0.249642)
							(end -0.2794 -0.1778)
						)
						(arc
							(start -0.2794 0.1778)
							(mid -0.249642 0.249642)
							(end -0.1778 0.2794)
						)
						(arc
							(start 0.1778 0.2794)
							(mid 0.249642 0.249642)
							(end 0.2794 0.1778)
						)
						(arc
							(start 0.2794 -0.1778)
							(mid 0.249642 -0.249642)
							(end 0.1778 -0.2794)
						)
					)
					(width 0)
					(fill yes)
				)
			)
		)
		(pad "2" smd custom
			(at 0 0.4445)
			(size 0.1397 0.1397)
			(layers "F.Cu" "F.Mask" "F.Paste")
			(net "GND")
			(options
				(clearance outline)
				(anchor circle)
			)
			(primitives
				(gr_poly
					(pts
						(arc
							(start -0.1778 -0.2794)
							(mid -0.249642 -0.249642)
							(end -0.2794 -0.1778)
						)
						(arc
							(start -0.2794 0.1778)
							(mid -0.249642 0.249642)
							(end -0.1778 0.2794)
						)
						(arc
							(start 0.1778 0.2794)
							(mid 0.249642 0.249642)
							(end 0.2794 0.1778)
						)
						(arc
							(start 0.2794 -0.1778)
							(mid 0.249642 -0.249642)
							(end 0.1778 -0.2794)
						)
					)
					(width 0)
					(fill yes)
				)
			)
		)
	)
	(footprint ""
		(layer "F.Cu")
		(at 330.099924 -7.999984 -90)
		(property "Reference" "LED15"
			(at 0 0 270)
			(layer "F.SilkS")
			(hide yes)
			(effects
				(font
					(size 1.27 1.27)
				)
			)
		)
		(property "Value" "LED-YG-51-GP"
			(at -2.6924 -1.4224 270)
			(unlocked yes)
			(layer "F.Fab")
			(hide yes)
			(effects
				(font
					(size 1.016 1.016)
					(thickness 0.1524)
				)
			)
		)
		(property "Device Type" "LED1608AKH40"
			(at -2.6924 -2.9464 270)
			(unlocked yes)
			(layer "F.Fab")
			(hide yes)
			(effects
				(font
					(size 1.016 1.016)
					(thickness 0.1524)
				)
			)
		)
		(duplicate_pad_numbers_are_jumpers no)
		(fp_line
			(start -0.7493 1.651)
			(end -0.7493 1.1811)
			(stroke
				(width 0.3302)
				(type default)
			)
			(layer "F.SilkS")
		)
		(fp_line
			(start 0.7493 1.651)
			(end 0.7493 1.1811)
			(stroke
				(width 0.3302)
				(type default)
			)
			(layer "F.SilkS")
		)
		(fp_line
			(start -0.5969 1.5494)
			(end 0.5842 1.5494)
			(stroke
				(width 0.508)
				(type default)
			)
			(layer "F.SilkS")
		)
		(fp_line
			(start -0.6604 1.3716)
			(end -0.6604 -1.3716)
			(stroke
				(width 0.1524)
				(type default)
			)
			(layer "F.SilkS")
		)
		(fp_line
			(start 0.6604 1.3716)
			(end -0.6604 1.3716)
			(stroke
				(width 0.1524)
				(type default)
			)
			(layer "F.SilkS")
		)
		(fp_line
			(start -0.6604 -1.3716)
			(end 0.6604 -1.3716)
			(stroke
				(width 0.1524)
				(type default)
			)
			(layer "F.SilkS")
		)
		(fp_line
			(start 0.6604 -1.3716)
			(end 0.6604 1.3716)
			(stroke
				(width 0.1524)
				(type default)
			)
			(layer "F.SilkS")
		)
		(fp_rect
			(start -0.6223 1.3335)
			(end 0.6223 -1.3335)
			(stroke
				(width 0)
				(type default)
			)
			(fill no)
			(layer "F.CrtYd")
		)
		(fp_rect
			(start -0.6223 1.3335)
			(end 0.6223 -1.3335)
			(stroke
				(width 0)
				(type default)
			)
			(fill no)
			(layer "F.Fab")
		)
		(pad "A" smd custom
			(at 0 -0.762 270)
			(size 0.2159 0.2159)
			(layers "F.Cu" "F.Mask" "F.Paste")
			(net "LED_R_7")
			(options
				(clearance outline)
				(anchor circle)
			)
			(primitives
				(gr_poly
					(pts
						(arc
							(start -0.3302 -0.4318)
							(mid -0.402042 -0.402042)
							(end -0.4318 -0.3302)
						)
						(arc
							(start -0.4318 0.3302)
							(mid -0.402042 0.402042)
							(end -0.3302 0.4318)
						)
						(arc
							(start 0.3302 0.4318)
							(mid 0.402042 0.402042)
							(end 0.4318 0.3302)
						)
						(arc
							(start 0.4318 -0.3302)
							(mid 0.402042 -0.402042)
							(end 0.3302 -0.4318)
						)
					)
					(width 0)
					(fill yes)
				)
			)
		)
		(pad "K" smd custom
			(at 0 0.762 270)
			(size 0.2159 0.2159)
			(layers "F.Cu" "F.Mask" "F.Paste")
			(net "LED_Q_7")
			(options
				(clearance outline)
				(anchor circle)
			)
			(primitives
				(gr_poly
					(pts
						(arc
							(start -0.3302 -0.4318)
							(mid -0.402042 -0.402042)
							(end -0.4318 -0.3302)
						)
						(arc
							(start -0.4318 0.3302)
							(mid -0.402042 0.402042)
							(end -0.3302 0.4318)
						)
						(arc
							(start 0.3302 0.4318)
							(mid 0.402042 0.402042)
							(end 0.4318 0.3302)
						)
						(arc
							(start 0.4318 -0.3302)
							(mid 0.402042 -0.402042)
							(end 0.3302 -0.4318)
						)
					)
					(width 0)
					(fill yes)
				)
			)
		)
	)
	(footprint ""
		(layer "F.Cu")
		(at 70.993 -32.004 90)
		(property "Reference" "PR33"
			(at 0 0 90)
			(layer "F.SilkS")
			(hide yes)
			(effects
				(font
					(size 1.27 1.27)
				)
			)
		)
		(property "Value" "44K2R2F-1-GP"
			(at 0.064008 -3.993896 90)
			(unlocked yes)
			(layer "F.Fab")
			(hide yes)
			(effects
				(font
					(size 1.016 1.016)
					(thickness 0.1524)
				)
			)
		)
		(property "Device Type" "R402H16"
			(at 0.064008 -5.517896 90)
			(unlocked yes)
			(layer "F.Fab")
			(hide yes)
			(effects
				(font
					(size 1.016 1.016)
					(thickness 0.1524)
				)
			)
		)
		(duplicate_pad_numbers_are_jumpers no)
		(fp_line
			(start 0.508 -0.9398)
			(end -0.508 -0.9398)
			(stroke
				(width 0.1524)
				(type default)
			)
			(layer "F.SilkS")
		)
		(fp_line
			(start -0.508 -0.9398)
			(end -0.508 0.9398)
			(stroke
				(width 0.1524)
				(type default)
			)
			(layer "F.SilkS")
		)
		(fp_rect
			(start -0.508 0.9398)
			(end 0.508 -0.9398)
			(stroke
				(width 0)
				(type default)
			)
			(fill no)
			(layer "F.CrtYd")
		)
		(fp_rect
			(start -0.508 0.9398)
			(end 0.508 -0.9398)
			(stroke
				(width 0)
				(type default)
			)
			(fill no)
			(layer "F.Fab")
		)
		(pad "1" smd custom
			(at 0 -0.4445 90)
			(size 0.1397 0.1397)
			(layers "F.Cu" "F.Mask" "F.Paste")
			(net "P3V3_STBY_VFB")
			(options
				(clearance outline)
				(anchor circle)
			)
			(primitives
				(gr_poly
					(pts
						(arc
							(start -0.1778 -0.2794)
							(mid -0.249642 -0.249642)
							(end -0.2794 -0.1778)
						)
						(arc
							(start -0.2794 0.1778)
							(mid -0.249642 0.249642)
							(end -0.1778 0.2794)
						)
						(arc
							(start 0.1778 0.2794)
							(mid 0.249642 0.249642)
							(end 0.2794 0.1778)
						)
						(arc
							(start 0.2794 -0.1778)
							(mid 0.249642 -0.249642)
							(end 0.1778 -0.2794)
						)
					)
					(width 0)
					(fill yes)
				)
			)
		)
		(pad "2" smd custom
			(at 0 0.4445 90)
			(size 0.1397 0.1397)
			(layers "F.Cu" "F.Mask" "F.Paste")
			(net "P3V3_STBY_VFB_R")
			(options
				(clearance outline)
				(anchor circle)
			)
			(primitives
				(gr_poly
					(pts
						(arc
							(start -0.1778 -0.2794)
							(mid -0.249642 -0.249642)
							(end -0.2794 -0.1778)
						)
						(arc
							(start -0.2794 0.1778)
							(mid -0.249642 0.249642)
							(end -0.1778 0.2794)
						)
						(arc
							(start 0.1778 0.2794)
							(mid 0.249642 0.249642)
							(end 0.2794 0.1778)
						)
						(arc
							(start 0.2794 -0.1778)
							(mid 0.249642 -0.249642)
							(end 0.1778 -0.2794)
						)
					)
					(width 0)
					(fill yes)
				)
			)
		)
	)
	(footprint ""
		(layer "F.Cu")
		(at 90.2081 -212.420454 180)
		(property "Reference" "C345"
			(at 0 0 180)
			(layer "F.SilkS")
			(hide yes)
			(effects
				(font
					(size 1.27 1.27)
				)
			)
		)
		(property "Value" "SCD22U10V2KX-1GP"
			(at 1.1811 -2.7051 180)
			(unlocked yes)
			(layer "F.Fab")
			(hide yes)
			(effects
				(font
					(size 1.016 1.016)
					(thickness 0.1524)
				)
			)
		)
		(property "Device Type" "C402H22"
			(at 1.1811 -4.2291 180)
			(unlocked yes)
			(layer "F.Fab")
			(hide yes)
			(effects
				(font
					(size 1.016 1.016)
					(thickness 0.1524)
				)
			)
		)
		(duplicate_pad_numbers_are_jumpers no)
		(fp_rect
			(start -0.4318 0.9525)
			(end 0.4318 -0.9525)
			(stroke
				(width 0)
				(type default)
			)
			(fill no)
			(layer "F.CrtYd")
		)
		(fp_rect
			(start -0.4318 0.9525)
			(end 0.4318 -0.9525)
			(stroke
				(width 0)
				(type default)
			)
			(fill no)
			(layer "F.Fab")
		)
		(pad "1" smd custom
			(at 0 -0.4445 180)
			(size 0.1524 0.1524)
			(layers "F.Cu" "F.Mask" "F.Paste")
			(net "PCIE_TX_CAP_N65")
			(options
				(clearance outline)
				(anchor circle)
			)
			(primitives
				(gr_poly
					(pts
						(arc
							(start 0.3048 -0.2032)
							(mid 0.275042 -0.275042)
							(end 0.2032 -0.3048)
						)
						(arc
							(start -0.2032 -0.3048)
							(mid -0.275042 -0.275042)
							(end -0.3048 -0.2032)
						)
						(arc
							(start -0.3048 0.2032)
							(mid -0.275042 0.275042)
							(end -0.2032 0.3048)
						)
						(arc
							(start 0.2032 0.3048)
							(mid 0.275042 0.275042)
							(end 0.3048 0.2032)
						)
					)
					(width 0)
					(fill yes)
				)
			)
		)
		(pad "2" smd custom
			(at 0 0.4445 180)
			(size 0.1524 0.1524)
			(layers "F.Cu" "F.Mask" "F.Paste")
			(net "PCIE_TX_N65")
			(options
				(clearance outline)
				(anchor circle)
			)
			(primitives
				(gr_poly
					(pts
						(arc
							(start 0.3048 -0.2032)
							(mid 0.275042 -0.275042)
							(end 0.2032 -0.3048)
						)
						(arc
							(start -0.2032 -0.3048)
							(mid -0.275042 -0.275042)
							(end -0.3048 -0.2032)
						)
						(arc
							(start -0.3048 0.2032)
							(mid -0.275042 0.275042)
							(end -0.2032 0.3048)
						)
						(arc
							(start 0.2032 0.3048)
							(mid 0.275042 0.275042)
							(end 0.3048 0.2032)
						)
					)
					(width 0)
					(fill yes)
				)
			)
		)
	)
)
